# T6G (Grand Teton) — schematic netlist excerpt (pin names and nets, part order shuffled) for the footprints in the layout excerpt that follows; sources: Cadence DE-HDL packaged netlist, KiCad conversion of 04192023_DAF0TMB3IC0_F0TG_MB_C_brd_V02_OCP.brd

R3464  Q_RES  54.9K 1% CHIP  pkg 0402LF  page 126 : A = P3V3_AUX ; B = GPU_FPGA_OVERT_N
R1325  Q_RES  0.002 1% CHIP  pkg 2512LF  page 357 : A = P12V_OCP_V3_2_R ; B = P12V_OCP_V3_2
R8047  Q_RES  0 5% CHIP  pkg 0402LF  page 200 : A = PVDDIO_P0_EN ; B = PVDDIO_P0_EN_R

(kicad_pcb
	(version 20260206)
	(generator "pcbnew")
	(generator_version "10.0")
	(general
		(thickness 1.6)
		(legacy_teardrops no)
	)
	(paper "A4")
	(title_block
		(title "04192023_DAF0TMB3IC0_F0TG_MB_C_brd_V02_OCP.brd")
		(comment 1 "Grand Teton / footprints 3317-3319 of 8354")
	)
	(layers
		(0 "F.Cu" signal "TOP")
		(4 "In1.Cu" signal "GND")
		(6 "In2.Cu" signal "IN1")
		(8 "In3.Cu" signal "GND1")
		(10 "In4.Cu" signal "IN2")
		(12 "In5.Cu" signal "GND2")
		(14 "In6.Cu" signal "IN3")
		(16 "In7.Cu" signal "GND3")
		(18 "In8.Cu" signal "VCC")
		(20 "In9.Cu" signal "VCC1")
		(22 "In10.Cu" signal "GND4")
		(24 "In11.Cu" signal "IN4")
		(26 "In12.Cu" signal "GND5")
		(28 "In13.Cu" signal "IN5")
		(30 "In14.Cu" signal "GND6")
		(32 "In15.Cu" signal "IN6")
		(34 "In16.Cu" signal "GND7")
		(2 "B.Cu" signal "BOTTOM")
		(9 "F.Adhes" user "F.Adhesive")
		(11 "B.Adhes" user "B.Adhesive")
		(13 "F.Paste" user "Package Geometry/Pastemask Top")
		(15 "B.Paste" user "Package Geometry/Pastemask Bottom")
		(5 "F.SilkS" user "Ref Des/Silkscreen Top")
		(7 "B.SilkS" user "Ref Des/Silkscreen Bottom")
		(1 "F.Mask" user "Board Geometry/Soldermask Top")
		(3 "B.Mask" user "Board Geometry/Soldermask Bottom")
		(17 "Dwgs.User" user "User.Drawings")
		(19 "Cmts.User" user "User.Comments")
		(21 "Eco1.User" user "User.Eco1")
		(23 "Eco2.User" user "User.Eco2")
		(25 "Edge.Cuts" user "Board Geometry/Outline")
		(27 "Margin" user)
		(31 "F.CrtYd" user "Package Geometry/Place Bound Top")
		(29 "B.CrtYd" user "Package Geometry/Place Bound Bottom")
		(35 "F.Fab" user "Ref Des/Assembly Top")
		(33 "B.Fab" user "Ref Des/Assembly Bottom")
	)
	(footprint ""
		(layer "F.Cu")
		(at 286.980884 -370.318792 90)
		(property "Reference" "R8047"
			(at 0 0 90)
			(layer "F.SilkS")
			(hide yes)
			(effects
				(font
					(size 1.27 1.27)
				)
			)
		)
		(property "Value" ""
			(at 0 0 90)
			(layer "F.Fab")
			(effects
				(font
					(size 1.27 1.27)
				)
			)
		)
		(duplicate_pad_numbers_are_jumpers no)
		(fp_line
			(start 0.7874 -0.4064)
			(end 0.7874 0.4064)
			(stroke
				(width 0.1524)
				(type default)
			)
			(layer "F.SilkS")
		)
		(fp_line
			(start -0.7874 -0.4064)
			(end 0.7874 -0.4064)
			(stroke
				(width 0.1524)
				(type default)
			)
			(layer "F.SilkS")
		)
		(fp_line
			(start 0.7874 0.4064)
			(end -0.7874 0.4064)
			(stroke
				(width 0.1524)
				(type default)
			)
			(layer "F.SilkS")
		)
		(fp_line
			(start -0.7874 0.4064)
			(end -0.7874 -0.4064)
			(stroke
				(width 0.1524)
				(type default)
			)
			(layer "F.SilkS")
		)
		(fp_line
			(start -0.12065 -0.305054)
			(end -0.12065 -0.2794)
			(stroke
				(width 0.1)
				(type default)
			)
			(layer "F.Fab")
		)
		(fp_line
			(start -0.67945 -0.305054)
			(end -0.12065 -0.305054)
			(stroke
				(width 0.1)
				(type default)
			)
			(layer "F.Fab")
		)
		(fp_line
			(start 0.67945 -0.3048)
			(end 0.67945 0.3048)
			(stroke
				(width 0.1)
				(type default)
			)
			(layer "F.Fab")
		)
		(fp_line
			(start 0.12065 -0.3048)
			(end 0.67945 -0.3048)
			(stroke
				(width 0.1)
				(type default)
			)
			(layer "F.Fab")
		)
		(fp_line
			(start 0.12065 -0.2794)
			(end 0.12065 -0.3048)
			(stroke
				(width 0.1)
				(type default)
			)
			(layer "F.Fab")
		)
		(fp_line
			(start -0.12065 -0.2794)
			(end 0.12065 -0.2794)
			(stroke
				(width 0.1)
				(type default)
			)
			(layer "F.Fab")
		)
		(fp_line
			(start 0.120396 0.2794)
			(end -0.12065 0.2794)
			(stroke
				(width 0.1)
				(type default)
			)
			(layer "F.Fab")
		)
		(fp_line
			(start -0.12065 0.2794)
			(end -0.12065 0.3048)
			(stroke
				(width 0.1)
				(type default)
			)
			(layer "F.Fab")
		)
		(fp_line
			(start 0.67945 0.3048)
			(end 0.120396 0.3048)
			(stroke
				(width 0.1)
				(type default)
			)
			(layer "F.Fab")
		)
		(fp_line
			(start 0.120396 0.3048)
			(end 0.120396 0.2794)
			(stroke
				(width 0.1)
				(type default)
			)
			(layer "F.Fab")
		)
		(fp_line
			(start -0.12065 0.3048)
			(end -0.67945 0.3048)
			(stroke
				(width 0.1)
				(type default)
			)
			(layer "F.Fab")
		)
		(fp_line
			(start -0.67945 0.3048)
			(end -0.67945 -0.305054)
			(stroke
				(width 0.1)
				(type default)
			)
			(layer "F.Fab")
		)
		(pad "1" smd circle
			(at -0.40005 0 90)
			(size 0 0)
			(layers "F.Cu" "F.Mask" "F.Paste")
			(net "PVDDIO_P0_EN")
		)
		(pad "2" smd circle
			(at 0.40005 0 90)
			(size 0 0)
			(layers "F.Cu" "F.Mask" "F.Paste")
			(net "PVDDIO_P0_EN_R")
		)
	)
	(footprint ""
		(layer "F.Cu")
		(at 71.035164 -16.315944)
		(property "Reference" "R1325"
			(at 1.889506 -2.226056 90)
			(unlocked yes)
			(layer "F.SilkS")
			(effects
				(font
					(size 0.7874 0.5842)
					(thickness 0.1524)
				)
				(justify left)
			)
		)
		(property "Value" ""
			(at 0 0 0)
			(layer "F.Fab")
			(effects
				(font
					(size 1.27 1.27)
				)
			)
		)
		(duplicate_pad_numbers_are_jumpers no)
		(fp_line
			(start -3.937508 -1.8796)
			(end -3.937508 1.8796)
			(stroke
				(width 0.1524)
				(type default)
			)
			(layer "F.SilkS")
		)
		(fp_line
			(start -3.937508 1.8796)
			(end 3.937508 1.8796)
			(stroke
				(width 0.1524)
				(type default)
			)
			(layer "F.SilkS")
		)
		(fp_line
			(start 3.937508 -1.8796)
			(end -3.937508 -1.8796)
			(stroke
				(width 0.1524)
				(type default)
			)
			(layer "F.SilkS")
		)
		(fp_line
			(start 3.937508 1.8796)
			(end 3.937508 -1.8796)
			(stroke
				(width 0.1524)
				(type default)
			)
			(layer "F.SilkS")
		)
		(fp_line
			(start -3.275076 -1.674876)
			(end -3.275076 1.674876)
			(stroke
				(width 0.1)
				(type default)
			)
			(layer "F.Fab")
		)
		(fp_line
			(start -3.275076 1.674876)
			(end 3.275076 1.674876)
			(stroke
				(width 0.1)
				(type default)
			)
			(layer "F.Fab")
		)
		(fp_line
			(start 3.275076 -1.674876)
			(end -3.275076 -1.674876)
			(stroke
				(width 0.1)
				(type default)
			)
			(layer "F.Fab")
		)
		(fp_line
			(start 3.275076 1.674876)
			(end 3.275076 -1.674876)
			(stroke
				(width 0.1)
				(type default)
			)
			(layer "F.Fab")
		)
		(pad "1" smd rect
			(at -2.350008 0)
			(size 2.921 3.5052)
			(layers "F.Cu" "F.Mask" "F.Paste")
			(net "P12V_OCP_V3_2_R")
		)
		(pad "2" smd rect
			(at 2.350008 0)
			(size 2.921 3.5052)
			(layers "F.Cu" "F.Mask" "F.Paste")
			(net "P12V_OCP_V3_2")
		)
	)
	(footprint ""
		(layer "F.Cu")
		(at 307.404516 -433.942744 90)
		(property "Reference" "R3464"
			(at 0 0 90)
			(layer "F.SilkS")
			(hide yes)
			(effects
				(font
					(size 1.27 1.27)
				)
			)
		)
		(property "Value" ""
			(at 0 0 90)
			(layer "F.Fab")
			(effects
				(font
					(size 1.27 1.27)
				)
			)
		)
		(duplicate_pad_numbers_are_jumpers no)
		(fp_line
			(start 0.7874 -0.4064)
			(end 0.7874 0.4064)
			(stroke
				(width 0.1524)
				(type default)
			)
			(layer "F.SilkS")
		)
		(fp_line
			(start -0.7874 -0.4064)
			(end 0.7874 -0.4064)
			(stroke
				(width 0.1524)
				(type default)
			)
			(layer "F.SilkS")
		)
		(fp_line
			(start 0.7874 0.4064)
			(end -0.7874 0.4064)
			(stroke
				(width 0.1524)
				(type default)
			)
			(layer "F.SilkS")
		)
		(fp_line
			(start -0.7874 0.4064)
			(end -0.7874 -0.4064)
			(stroke
				(width 0.1524)
				(type default)
			)
			(layer "F.SilkS")
		)
		(fp_line
			(start -0.12065 -0.305054)
			(end -0.12065 -0.2794)
			(stroke
				(width 0.1)
				(type default)
			)
			(layer "F.Fab")
		)
		(fp_line
			(start -0.67945 -0.305054)
			(end -0.12065 -0.305054)
			(stroke
				(width 0.1)
				(type default)
			)
			(layer "F.Fab")
		)
		(fp_line
			(start 0.67945 -0.3048)
			(end 0.67945 0.3048)
			(stroke
				(width 0.1)
				(type default)
			)
			(layer "F.Fab")
		)
		(fp_line
			(start 0.12065 -0.3048)
			(end 0.67945 -0.3048)
			(stroke
				(width 0.1)
				(type default)
			)
			(layer "F.Fab")
		)
		(fp_line
			(start 0.12065 -0.2794)
			(end 0.12065 -0.3048)
			(stroke
				(width 0.1)
				(type default)
			)
			(layer "F.Fab")
		)
		(fp_line
			(start -0.12065 -0.2794)
			(end 0.12065 -0.2794)
			(stroke
				(width 0.1)
				(type default)
			)
			(layer "F.Fab")
		)
		(fp_line
			(start 0.120396 0.2794)
			(end -0.12065 0.2794)
			(stroke
				(width 0.1)
				(type default)
			)
			(layer "F.Fab")
		)
		(fp_line
			(start -0.12065 0.2794)
			(end -0.12065 0.3048)
			(stroke
				(width 0.1)
				(type default)
			)
			(layer "F.Fab")
		)
		(fp_line
			(start 0.67945 0.3048)
			(end 0.120396 0.3048)
			(stroke
				(width 0.1)
				(type default)
			)
			(layer "F.Fab")
		)
		(fp_line
			(start 0.120396 0.3048)
			(end 0.120396 0.2794)
			(stroke
				(width 0.1)
				(type default)
			)
			(layer "F.Fab")
		)
		(fp_line
			(start -0.12065 0.3048)
			(end -0.67945 0.3048)
			(stroke
				(width 0.1)
				(type default)
			)
			(layer "F.Fab")
		)
		(fp_line
			(start -0.67945 0.3048)
			(end -0.67945 -0.305054)
			(stroke
				(width 0.1)
				(type default)
			)
			(layer "F.Fab")
		)
		(pad "1" smd circle
			(at -0.40005 0 90)
			(size 0 0)
			(layers "F.Cu" "F.Mask" "F.Paste")
			(net "P3V3_AUX")
		)
		(pad "2" smd circle
			(at 0.40005 0 90)
			(size 0 0)
			(layers "F.Cu" "F.Mask" "F.Paste")
			(net "GPU_FPGA_OVERT_N")
		)
	)
)
